(kicad_pcb
	(version 20241229)
	(generator "pcbnew")
	(generator_version "9.0")
	(general
		(thickness 1.552)
		(legacy_teardrops no)
	)
	(paper "A4")
	(title_block
		(date "2023-07-25")
		(rev "1.1.4")
		(comment 9 "footprints 196-200 of 379")
	)
	(layers
		(0 "F.Cu" signal)
		(4 "In1.Cu" signal)
		(6 "In2.Cu" signal)
		(8 "In3.Cu" signal)
		(10 "In4.Cu" signal)
		(12 "In5.Cu" signal)
		(14 "In6.Cu" signal)
		(2 "B.Cu" signal)
		(9 "F.Adhes" user "F.Adhesive")
		(11 "B.Adhes" user "B.Adhesive")
		(13 "F.Paste" user)
		(15 "B.Paste" user)
		(5 "F.SilkS" user "F.Silkscreen")
		(7 "B.SilkS" user "B.Silkscreen")
		(1 "F.Mask" user)
		(3 "B.Mask" user)
		(17 "Dwgs.User" user "User.Drawings")
		(19 "Cmts.User" user "User.Comments")
		(21 "Eco1.User" user "User.Eco1")
		(23 "Eco2.User" user "User.Eco2")
		(25 "Edge.Cuts" user)
		(27 "Margin" user)
		(31 "F.CrtYd" user "F.Courtyard")
		(29 "B.CrtYd" user "B.Courtyard")
		(35 "F.Fab" user)
		(33 "B.Fab" user)
	)
	(footprint "antmicro-footprints:LED_0603_1608Metric_R"
		(layer "F.Cu")
		(at 124.03 109.65 -90)
		(descr "LED SMD 0603 Red")
		(tags "LED SMD 0603 Red")
		(property "Reference" "D6"
			(at -2.71 0.4 90)
			(layer "F.SilkS")
			(effects
				(font
					(size 0.65 0.65)
					(thickness 0.15)
				)
				(justify right top)
			)
		)
		(property "Value" "LED_R_0603_LTST-C190KRKT"
			(at 0 1.6 90)
			(layer "F.Fab")
			(hide yes)
			(effects
				(font
					(size 0.7 0.7)
					(thickness 0.15)
				)
				(justify right top)
			)
		)
		(property "Datasheet" "https://optoelectronics.liteon.com/upload/download/DS-22-99-0151/LTST-C190KRKT.pdf"
			(at 0 0 90)
			(layer "F.Fab")
			(hide yes)
			(effects
				(font
					(size 1.27 1.27)
					(thickness 0.15)
				)
			)
		)
		(property "Description" "LED, Red, SMD, 0603, 25 mA, 2 V, 631 nm"
			(at 0 0 90)
			(layer "F.Fab")
			(hide yes)
			(effects
				(font
					(size 1.27 1.27)
					(thickness 0.15)
				)
			)
		)
		(property "Author" "Antmicro"
			(at 233.68 -14.38 0)
			(layer "F.Fab")
			(hide yes)
			(effects
				(font
					(size 1 1)
					(thickness 0.15)
				)
			)
		)
		(property "License" "Apache-2.0"
			(at 233.68 -14.38 0)
			(layer "F.Fab")
			(hide yes)
			(effects
				(font
					(size 1 1)
					(thickness 0.15)
				)
			)
		)
		(property "MPN" "LTST-C190KRKT"
			(at 233.68 -14.38 0)
			(layer "F.Fab")
			(hide yes)
			(effects
				(font
					(size 1 1)
					(thickness 0.15)
				)
			)
		)
		(property "Manufacturer" "Lite-On"
			(at 233.68 -14.38 0)
			(layer "F.Fab")
			(hide yes)
			(effects
				(font
					(size 1 1)
					(thickness 0.15)
				)
			)
		)
		(property "Color" "Red"
			(at 0 0 270)
			(unlocked yes)
			(layer "F.Fab")
			(hide yes)
			(effects
				(font
					(size 1 1)
					(thickness 0.15)
				)
			)
		)
		(sheetname "/FPGA/")
		(sheetfile "fpga.kicad_sch")
		(attr smd)
		(fp_line
			(start 0.22 0.35)
			(end -0.22 0.35)
			(stroke
				(width 0.15)
				(type solid)
			)
			(layer "F.SilkS")
		)
		(fp_line
			(start -0.094672 0.201008)
			(end -0.094672 -0.198992)
			(stroke
				(width 0.1)
				(type solid)
			)
			(layer "F.SilkS")
		)
		(fp_line
			(start 0.105328 0.201008)
			(end -0.094672 0.001008)
			(stroke
				(width 0.1)
				(type solid)
			)
			(layer "F.SilkS")
		)
		(fp_line
			(start 0.105328 0.201008)
			(end 0.105328 -0.198992)
			(stroke
				(width 0.1)
				(type solid)
			)
			(layer "F.SilkS")
		)
		(fp_line
			(start -0.094672 0.001008)
			(end -0.24 0.001008)
			(stroke
				(width 0.1)
				(type solid)
			)
			(layer "F.SilkS")
		)
		(fp_line
			(start -0.094672 0.001008)
			(end 0.105328 -0.198992)
			(stroke
				(width 0.1)
				(type solid)
			)
			(layer "F.SilkS")
		)
		(fp_line
			(start 0.105328 0.001008)
			(end 0.24 0.001)
			(stroke
				(width 0.1)
				(type solid)
			)
			(layer "F.SilkS")
		)
		(fp_line
			(start -1.18 -0.319)
			(end -1.18 0.321)
			(stroke
				(width 0.15)
				(type solid)
			)
			(layer "F.SilkS")
		)
		(fp_line
			(start 0.22 -0.35)
			(end -0.22 -0.35)
			(stroke
				(width 0.15)
				(type solid)
			)
			(layer "F.SilkS")
		)
		(fp_rect
			(start 1.25 0.65)
			(end -1.25 -0.65)
			(stroke
				(width 0.05)
				(type solid)
			)
			(fill no)
			(layer "F.CrtYd")
		)
		(fp_line
			(start -0.199 0.2)
			(end -0.199 0.1)
			(stroke
				(width 0.15)
				(type solid)
			)
			(layer "F.Fab")
		)
		(fp_line
			(start 0.201 0.2)
			(end 0.201 0)
			(stroke
				(width 0.15)
				(type solid)
			)
			(layer "F.Fab")
		)
		(fp_line
			(start -0.199 0)
			(end -0.597 0)
			(stroke
				(width 0.15)
				(type solid)
			)
			(layer "F.Fab")
		)
		(fp_line
			(start -0.101 0)
			(end 0.201 0.2)
			(stroke
				(width 0.15)
				(type solid)
			)
			(layer "F.Fab")
		)
		(fp_line
			(start 0.201 0)
			(end 0.201 -0.202)
			(stroke
				(width 0.15)
				(type solid)
			)
			(layer "F.Fab")
		)
		(fp_line
			(start 0.599 0)
			(end 0.201 0)
			(stroke
				(width 0.15)
				(type solid)
			)
			(layer "F.Fab")
		)
		(fp_line
			(start -0.199 -0.202)
			(end -0.199 0.1)
			(stroke
				(width 0.15)
				(type solid)
			)
			(layer "F.Fab")
		)
		(fp_line
			(start 0.201 -0.202)
			(end -0.101 0)
			(stroke
				(width 0.15)
				(type solid)
			)
			(layer "F.Fab")
		)
		(fp_rect
			(start 0.848 0.4)
			(end -0.85 -0.402)
			(stroke
				(width 0.15)
				(type solid)
			)
			(fill no)
			(layer "F.Fab")
		)
		(fp_text user "${REFERENCE}"
			(at -1.31 3.769 90)
			(layer "F.Fab")
			(effects
				(font
					(size 0.7 0.7)
					(thickness 0.15)
				)
				(justify right top)
			)
		)
		(fp_text user "License: Apache-2.0"
			(at -1.31 5.769 90)
			(layer "F.Fab")
			(effects
				(font
					(size 0.7 0.7)
					(thickness 0.15)
				)
				(justify right top)
			)
		)
		(fp_text user "Author: Antmicro"
			(at -1.31 4.769 90)
			(layer "F.Fab")
			(effects
				(font
					(size 0.7 0.7)
					(thickness 0.15)
				)
				(justify right top)
			)
		)
		(pad "1" smd roundrect
			(at -0.7 0 90)
			(size 0.8 1)
			(layers "F.Cu" "F.Mask" "F.Paste")
			(roundrect_rratio 0.2)
			(net 15 "/FPGA/INITN")
			(pinfunction "C")
			(pintype "passive")
		)
		(pad "2" smd roundrect
			(at 0.7 0 90)
			(size 0.8 1)
			(layers "F.Cu" "F.Mask" "F.Paste")
			(roundrect_rratio 0.2)
			(net 245 "Net-(D6-A)")
			(pinfunction "A")
			(pintype "passive")
		)
	)
	(footprint "antmicro-footprints:R_0402_1005Metric"
		(layer "F.Cu")
		(at 133.83 110.15 180)
		(descr "Resistor SMD 0402")
		(tags "resistor SMD 0402")
		(property "Reference" "R68"
			(at 3.2 0.01 180)
			(layer "F.SilkS")
			(effects
				(font
					(size 0.65 0.65)
					(thickness 0.15)
				)
				(justify left bottom)
			)
		)
		(property "Value" "R_10k_0402"
			(at 0 1.4 180)
			(layer "F.Fab")
			(hide yes)
			(effects
				(font
					(size 0.7 0.7)
					(thickness 0.15)
				)
				(justify left bottom)
			)
		)
		(property "Datasheet" "https://www.bourns.com/docs/product-datasheets/cr.pdf"
			(at 0 0 180)
			(layer "F.Fab")
			(hide yes)
			(effects
				(font
					(size 1.27 1.27)
					(thickness 0.15)
				)
			)
		)
		(property "Description" "SMD Chip Resistor, 10 kohm, ± 1%, 62.5 mW, 0402 [1005 Metric], Thick Film, General Purpose"
			(at 0 0 180)
			(layer "F.Fab")
			(hide yes)
			(effects
				(font
					(size 1.27 1.27)
					(thickness 0.15)
				)
			)
		)
		(property "Author" "Antmicro"
			(at 267.66 220.3 0)
			(layer "F.Fab")
			(hide yes)
			(effects
				(font
					(size 1 1)
					(thickness 0.15)
				)
			)
		)
		(property "License" "Apache-2.0"
			(at 267.66 220.3 0)
			(layer "F.Fab")
			(hide yes)
			(effects
				(font
					(size 1 1)
					(thickness 0.15)
				)
			)
		)
		(property "MPN" "CR0402-FX-1002GLF"
			(at 267.66 220.3 0)
			(layer "F.Fab")
			(hide yes)
			(effects
				(font
					(size 1 1)
					(thickness 0.15)
				)
			)
		)
		(property "Manufacturer" "Bourns"
			(at 267.66 220.3 0)
			(layer "F.Fab")
			(hide yes)
			(effects
				(font
					(size 1 1)
					(thickness 0.15)
				)
			)
		)
		(property "Tolerance" "1%"
			(at 267.66 220.3 0)
			(layer "F.Fab")
			(hide yes)
			(effects
				(font
					(size 1 1)
					(thickness 0.15)
				)
			)
		)
		(property "Val" "10k"
			(at 267.66 220.3 0)
			(layer "F.Fab")
			(hide yes)
			(effects
				(font
					(size 1 1)
					(thickness 0.15)
				)
			)
		)
		(sheetname "/FPGA/")
		(sheetfile "fpga.kicad_sch")
		(attr smd)
		(fp_rect
			(start -0.925 -0.47)
			(end 0.925 0.47)
			(stroke
				(width 0.05)
				(type default)
			)
			(fill no)
			(layer "F.CrtYd")
		)
		(fp_rect
			(start -0.5 -0.25)
			(end 0.5 0.25)
			(stroke
				(width 0.15)
				(type solid)
			)
			(fill no)
			(layer "F.Fab")
		)
		(fp_text user "${REFERENCE}"
			(at -0.95 3.168 180)
			(layer "F.Fab")
			(effects
				(font
					(size 0.7 0.7)
					(thickness 0.15)
				)
				(justify left bottom)
			)
		)
		(fp_text user "Author: Antmicro"
			(at -0.95 4.169 180)
			(layer "F.Fab")
			(effects
				(font
					(size 0.7 0.7)
					(thickness 0.15)
				)
				(justify left bottom)
			)
		)
		(fp_text user "License: Apache-2.0"
			(at -0.95 5.169 180)
			(layer "F.Fab")
			(effects
				(font
					(size 0.7 0.7)
					(thickness 0.15)
				)
				(justify left bottom)
			)
		)
		(pad "1" smd roundrect
			(at -0.48 0 180)
			(size 0.59 0.64)
			(layers "F.Cu" "F.Mask" "F.Paste")
			(roundrect_rratio 0.25)
			(net 36 "/FPGA/PROGRAMN")
			(pintype "passive")
		)
		(pad "2" smd roundrect
			(at 0.48 0 180)
			(size 0.59 0.64)
			(layers "F.Cu" "F.Mask" "F.Paste")
			(roundrect_rratio 0.25)
			(net 2 "+3V3")
			(pintype "passive")
		)
	)
	(footprint "antmicro-footprints:R_0603_1608Metric"
		(layer "F.Cu")
		(at 169.9 77.73 180)
		(descr "Resistor SMD 0603")
		(tags "resistor SMD 0603")
		(property "Reference" "R120"
			(at 1.46 0.86 180)
			(layer "F.SilkS")
			(effects
				(font
					(size 0.65 0.65)
					(thickness 0.15)
				)
				(justify left bottom)
			)
		)
		(property "Value" "R_200R_0603"
			(at 0 1.6 180)
			(layer "F.Fab")
			(hide yes)
			(effects
				(font
					(size 0.7 0.7)
					(thickness 0.15)
				)
				(justify left bottom)
			)
		)
		(property "Datasheet" "https://www.bourns.com/docs/product-datasheets/cr.pdf"
			(at 0 0 180)
			(layer "F.Fab")
			(hide yes)
			(effects
				(font
					(size 1.27 1.27)
					(thickness 0.15)
				)
			)
		)
		(property "Description" "SMD Chip Resistor, 200 ohm, ± 1%, 100 mW, 0603 [1608 Metric], Thick Film, General Purpose"
			(at 0 0 180)
			(layer "F.Fab")
			(hide yes)
			(effects
				(font
					(size 1.27 1.27)
					(thickness 0.15)
				)
			)
		)
		(property "Author" "Antmicro"
			(at 339.78 155.6 0)
			(layer "F.Fab")
			(hide yes)
			(effects
				(font
					(size 1 1)
					(thickness 0.15)
				)
			)
		)
		(property "License" "Apache-2.0"
			(at 339.78 155.6 0)
			(layer "F.Fab")
			(hide yes)
			(effects
				(font
					(size 1 1)
					(thickness 0.15)
				)
			)
		)
		(property "MPN" "CR0603-FX-2000ELF"
			(at 339.78 155.6 0)
			(layer "F.Fab")
			(hide yes)
			(effects
				(font
					(size 1 1)
					(thickness 0.15)
				)
			)
		)
		(property "Manufacturer" "Bourns"
			(at 339.78 155.6 0)
			(layer "F.Fab")
			(hide yes)
			(effects
				(font
					(size 1 1)
					(thickness 0.15)
				)
			)
		)
		(property "Tolerance" "1%"
			(at 339.78 155.6 0)
			(layer "F.Fab")
			(hide yes)
			(effects
				(font
					(size 1 1)
					(thickness 0.15)
				)
			)
		)
		(property "Val" "200R"
			(at 339.78 155.6 0)
			(layer "F.Fab")
			(hide yes)
			(effects
				(font
					(size 1 1)
					(thickness 0.15)
				)
			)
		)
		(sheetname "/Peripherals/")
		(sheetfile "peripherals.kicad_sch")
		(attr smd)
		(fp_line
			(start -0.15 0.4)
			(end 0.15 0.4)
			(stroke
				(width 0.15)
				(type solid)
			)
			(layer "F.SilkS")
		)
		(fp_line
			(start -0.15 -0.4)
			(end 0.15 -0.4)
			(stroke
				(width 0.15)
				(type solid)
			)
			(layer "F.SilkS")
		)
		(fp_rect
			(start -1.25 -0.65)
			(end 1.25 0.65)
			(stroke
				(width 0.05)
				(type solid)
			)
			(fill no)
			(layer "F.CrtYd")
		)
		(fp_rect
			(start -0.8 -0.4)
			(end 0.8 0.4)
			(stroke
				(width 0.15)
				(type solid)
			)
			(fill no)
			(layer "F.Fab")
		)
		(fp_text user "Author: Antmicro"
			(at -1.25 4.9 180)
			(layer "F.Fab")
			(effects
				(font
					(size 0.7 0.7)
					(thickness 0.15)
				)
				(justify left bottom)
			)
		)
		(fp_text user "${REFERENCE}"
			(at -1.25 3.898 180)
			(layer "F.Fab")
			(effects
				(font
					(size 0.7 0.7)
					(thickness 0.15)
				)
				(justify left bottom)
			)
		)
		(fp_text user "License: Apache-2.0"
			(at -1.25 5.9 180)
			(layer "F.Fab")
			(effects
				(font
					(size 0.7 0.7)
					(thickness 0.15)
				)
				(justify left bottom)
			)
		)
		(pad "1" smd roundrect
			(at -0.7 0 180)
			(size 0.8 1)
			(layers "F.Cu" "F.Mask" "F.Paste")
			(roundrect_rratio 0.2)
			(net 257 "Net-(D11-A)")
			(pintype "passive")
		)
		(pad "2" smd roundrect
			(at 0.7 0 180)
			(size 0.8 1)
			(layers "F.Cu" "F.Mask" "F.Paste")
			(roundrect_rratio 0.2)
			(net 310 "/Peripherals/QWIIC_3V3")
			(pintype "passive")
		)
	)
	(footprint "antmicro-footprints:R_0402_1005Metric"
		(layer "F.Cu")
		(at 107.9 90.24 180)
		(descr "Resistor SMD 0402")
		(tags "resistor SMD 0402")
		(property "Reference" "R82"
			(at 1.17 0.676084 180)
			(layer "F.SilkS")
			(effects
				(font
					(size 0.65 0.65)
					(thickness 0.15)
				)
				(justify left bottom)
			)
		)
		(property "Value" "R_0R_0402"
			(at 0 1.4 180)
			(layer "F.Fab")
			(hide yes)
			(effects
				(font
					(size 0.7 0.7)
					(thickness 0.15)
				)
				(justify left bottom)
			)
		)
		(property "Datasheet" "https://industrial.panasonic.com/cdbs/www-data/pdf/RDA0000/AOA0000C301.pdf"
			(at 0 0 180)
			(layer "F.Fab")
			(hide yes)
			(effects
				(font
					(size 1.27 1.27)
					(thickness 0.15)
				)
			)
		)
		(property "Description" "SMD Chip Resistor, Jumper, 0 ohm, 100 mW, 0402 [1005 Metric], Thick Film, General Purpose"
			(at 0 0 180)
			(layer "F.Fab")
			(hide yes)
			(effects
				(font
					(size 1.27 1.27)
					(thickness 0.15)
				)
			)
		)
		(property "Author" "Antmicro"
			(at 215.8 180.48 0)
			(layer "F.Fab")
			(hide yes)
			(effects
				(font
					(size 1 1)
					(thickness 0.15)
				)
			)
		)
		(property "Current" "1A"
			(at 215.8 180.48 0)
			(layer "F.Fab")
			(hide yes)
			(effects
				(font
					(size 1 1)
					(thickness 0.15)
				)
			)
		)
		(property "License" "Apache-2.0"
			(at 215.8 180.48 0)
			(layer "F.Fab")
			(hide yes)
			(effects
				(font
					(size 1 1)
					(thickness 0.15)
				)
			)
		)
		(property "MPN" "ERJ2GE0R00X"
			(at 215.8 180.48 0)
			(layer "F.Fab")
			(hide yes)
			(effects
				(font
					(size 1 1)
					(thickness 0.15)
				)
			)
		)
		(property "Manufacturer" "Panasonic"
			(at 215.8 180.48 0)
			(layer "F.Fab")
			(hide yes)
			(effects
				(font
					(size 1 1)
					(thickness 0.15)
				)
			)
		)
		(property "Tolerance" "~"
			(at 215.8 180.48 0)
			(layer "F.Fab")
			(hide yes)
			(effects
				(font
					(size 1 1)
					(thickness 0.15)
				)
			)
		)
		(property "Val" "0R"
			(at 215.8 180.48 0)
			(layer "F.Fab")
			(hide yes)
			(effects
				(font
					(size 1 1)
					(thickness 0.15)
				)
			)
		)
		(sheetname "/FPGA/")
		(sheetfile "fpga.kicad_sch")
		(attr smd)
		(fp_rect
			(start -0.925 -0.47)
			(end 0.925 0.47)
			(stroke
				(width 0.05)
				(type default)
			)
			(fill no)
			(layer "F.CrtYd")
		)
		(fp_rect
			(start -0.5 -0.25)
			(end 0.5 0.25)
			(stroke
				(width 0.15)
				(type solid)
			)
			(fill no)
			(layer "F.Fab")
		)
		(fp_text user "Author: Antmicro"
			(at -0.95 4.169 180)
			(layer "F.Fab")
			(effects
				(font
					(size 0.7 0.7)
					(thickness 0.15)
				)
				(justify left bottom)
			)
		)
		(fp_text user "${REFERENCE}"
			(at -0.95 3.168 180)
			(layer "F.Fab")
			(effects
				(font
					(size 0.7 0.7)
					(thickness 0.15)
				)
				(justify left bottom)
			)
		)
		(fp_text user "License: Apache-2.0"
			(at -0.95 5.169 180)
			(layer "F.Fab")
			(effects
				(font
					(size 0.7 0.7)
					(thickness 0.15)
				)
				(justify left bottom)
			)
		)
		(pad "1" smd roundrect
			(at -0.48 0 180)
			(size 0.59 0.64)
			(layers "F.Cu" "F.Mask" "F.Paste")
			(roundrect_rratio 0.25)
			(net 324 "Net-(U21-D4)")
			(pintype "passive")
		)
		(pad "2" smd roundrect
			(at 0.48 0 180)
			(size 0.59 0.64)
			(layers "F.Cu" "F.Mask" "F.Paste")
			(roundrect_rratio 0.25)
			(net 306 "Net-(U18-~{CS})")
			(pintype "passive")
		)
	)
	(footprint "antmicro-footprints:MP_Pad5.4mm_Drill2.7mm"
		(layer "F.Cu")
		(at 170.03 60.15)
		(descr "Mounting Hole 2.7mm, M2.5")
		(tags "mounting hole 2.7mm m2.5")
		(property "Reference" "MP3"
			(at 0 -2.9 0)
			(layer "F.SilkS")
			(hide yes)
			(effects
				(font
					(size 0.7 0.7)
					(thickness 0.15)
				)
				(justify left bottom)
			)
		)
		(property "Value" "MP_Pad5.4mm_Drill2.7mm"
			(at 0 3.6 0)
			(layer "F.Fab")
			(effects
				(font
					(size 0.7 0.7)
					(thickness 0.15)
				)
				(justify left bottom)
			)
		)
		(property "Description" "Mechanical part"
			(at 0 0 0)
			(layer "F.Fab")
			(hide yes)
			(effects
				(font
					(size 1.27 1.27)
					(thickness 0.15)
				)
			)
		)
		(property "Author" "Antmicro"
			(at 0 0 0)
			(unlocked yes)
			(layer "F.Fab")
			(hide yes)
			(effects
				(font
					(size 1 1)
					(thickness 0.15)
				)
			)
		)
		(property "License" "Apache-2.0"
			(at 0 0 0)
			(unlocked yes)
			(layer "F.Fab")
			(hide yes)
			(effects
				(font
					(size 1 1)
					(thickness 0.15)
				)
			)
		)
		(sheetname "/")
		(sheetfile "sdi-mipi-video-converter.kicad_sch")
		(attr exclude_from_pos_files exclude_from_bom)
		(fp_circle
			(center 0 0)
			(end 2.95 0)
			(stroke
				(width 0.05)
				(type default)
			)
			(fill no)
			(layer "F.CrtYd")
		)
		(fp_text user "Author: Antmicro"
			(at -8.4 7.2 0)
			(layer "F.Fab")
			(effects
				(font
					(size 0.7 0.7)
					(thickness 0.15)
				)
				(justify left bottom)
			)
		)
		(fp_text user "${REFERENCE}"
			(at -8.4 6 0)
			(layer "F.Fab")
			(effects
				(font
					(size 0.7 0.7)
					(thickness 0.15)
				)
				(justify left bottom)
			)
		)
		(fp_text user "License: Apache-2.0"
			(at -8.4 8.4 0)
			(layer "F.Fab")
			(effects
				(font
					(size 0.7 0.7)
					(thickness 0.15)
				)
				(justify left bottom)
			)
		)
		(pad "1" thru_hole circle
			(at 0 0)
			(size 5.4 5.4)
			(drill 2.7)
			(layers "*.Cu" "*.Mask")
			(remove_unused_layers no)
			(net 400 "unconnected-(MP3-Pad1)")
			(pintype "passive+no_connect")
			(solder_paste_margin_ratio -1)
		)
	)
)
